# S9S_MB_2U (Grand Teton) — schematic netlist excerpt (pin names and nets, part order shuffled) for the footprints in the layout excerpt that follows; sources: Cadence DE-HDL packaged netlist, KiCad conversion of 03242023_DA0F0TMBIJ0_F0T_Motherboard_J_brd_V01_OCP.brd

R3836  Q_RES  10K 1% CHIP  pkg 0402LF  page 242 : A = P3V3_AUX ; B = HP_LVC3_SCM_HSC_PWRGD_R
R2339  Q_RES  22 5% CHIP  pkg 0402LF  page 218 : A = LED_CPU_RMCA_CATERR_R ; B = GND

(kicad_pcb
	(version 20260206)
	(generator "pcbnew")
	(generator_version "10.0")
	(general
		(thickness 1.6)
		(legacy_teardrops no)
	)
	(paper "A4")
	(title_block
		(title "03242023_DA0F0TMBIJ0_F0T_Motherboard_J_brd_V01_OCP.brd")
		(comment 1 "Grand Teton / footprints 2605-2606 of 6105")
	)
	(layers
		(0 "F.Cu" signal "TOP")
		(4 "In1.Cu" signal "GND")
		(6 "In2.Cu" signal "IN1")
		(8 "In3.Cu" signal "GND1")
		(10 "In4.Cu" signal "IN2")
		(12 "In5.Cu" signal "GND2")
		(14 "In6.Cu" signal "IN3")
		(16 "In7.Cu" signal "GND3")
		(18 "In8.Cu" signal "VCC")
		(20 "In9.Cu" signal "VCC1")
		(22 "In10.Cu" signal "GND4")
		(24 "In11.Cu" signal "IN4")
		(26 "In12.Cu" signal "GND5")
		(28 "In13.Cu" signal "IN5")
		(30 "In14.Cu" signal "GND6")
		(32 "In15.Cu" signal "IN6")
		(34 "In16.Cu" signal "GND7")
		(2 "B.Cu" signal "BOTTOM")
		(9 "F.Adhes" user "F.Adhesive")
		(11 "B.Adhes" user "B.Adhesive")
		(13 "F.Paste" user "Package Geometry/Pastemask Top")
		(15 "B.Paste" user "Package Geometry/Pastemask Bottom")
		(5 "F.SilkS" user "Ref Des/Silkscreen Top")
		(7 "B.SilkS" user "Ref Des/Silkscreen Bottom")
		(1 "F.Mask" user "Board Geometry/Soldermask Top")
		(3 "B.Mask" user "Board Geometry/Soldermask Bottom")
		(17 "Dwgs.User" user "User.Drawings")
		(19 "Cmts.User" user "User.Comments")
		(21 "Eco1.User" user "User.Eco1")
		(23 "Eco2.User" user "User.Eco2")
		(25 "Edge.Cuts" user "Board Geometry/Outline")
		(27 "Margin" user)
		(31 "F.CrtYd" user "Package Geometry/Place Bound Top")
		(29 "B.CrtYd" user "Package Geometry/Place Bound Bottom")
		(35 "F.Fab" user "Ref Des/Assembly Top")
		(33 "B.Fab" user "Ref Des/Assembly Bottom")
	)
	(footprint ""
		(layer "F.Cu")
		(at 173.216062 -29.430472)
		(property "Reference" "R3836"
			(at 0 0 0)
			(layer "F.SilkS")
			(hide yes)
			(effects
				(font
					(size 1.27 1.27)
				)
			)
		)
		(property "Value" ""
			(at 0 0 0)
			(layer "F.Fab")
			(effects
				(font
					(size 1.27 1.27)
				)
			)
		)
		(duplicate_pad_numbers_are_jumpers no)
		(fp_line
			(start -0.7874 -0.4064)
			(end 0.7874 -0.4064)
			(stroke
				(width 0.1524)
				(type default)
			)
			(layer "F.SilkS")
		)
		(fp_line
			(start -0.7874 0.4064)
			(end -0.7874 -0.4064)
			(stroke
				(width 0.1524)
				(type default)
			)
			(layer "F.SilkS")
		)
		(fp_line
			(start 0.7874 -0.4064)
			(end 0.7874 0.4064)
			(stroke
				(width 0.1524)
				(type default)
			)
			(layer "F.SilkS")
		)
		(fp_line
			(start 0.7874 0.4064)
			(end -0.7874 0.4064)
			(stroke
				(width 0.1524)
				(type default)
			)
			(layer "F.SilkS")
		)
		(fp_line
			(start -0.67945 -0.305054)
			(end -0.12065 -0.305054)
			(stroke
				(width 0.1)
				(type default)
			)
			(layer "F.Fab")
		)
		(fp_line
			(start -0.67945 0.3048)
			(end -0.67945 -0.305054)
			(stroke
				(width 0.1)
				(type default)
			)
			(layer "F.Fab")
		)
		(fp_line
			(start -0.12065 -0.305054)
			(end -0.12065 -0.2794)
			(stroke
				(width 0.1)
				(type default)
			)
			(layer "F.Fab")
		)
		(fp_line
			(start -0.12065 -0.2794)
			(end 0.12065 -0.2794)
			(stroke
				(width 0.1)
				(type default)
			)
			(layer "F.Fab")
		)
		(fp_line
			(start -0.12065 0.2794)
			(end -0.12065 0.3048)
			(stroke
				(width 0.1)
				(type default)
			)
			(layer "F.Fab")
		)
		(fp_line
			(start -0.12065 0.3048)
			(end -0.67945 0.3048)
			(stroke
				(width 0.1)
				(type default)
			)
			(layer "F.Fab")
		)
		(fp_line
			(start 0.120396 0.2794)
			(end -0.12065 0.2794)
			(stroke
				(width 0.1)
				(type default)
			)
			(layer "F.Fab")
		)
		(fp_line
			(start 0.120396 0.3048)
			(end 0.120396 0.2794)
			(stroke
				(width 0.1)
				(type default)
			)
			(layer "F.Fab")
		)
		(fp_line
			(start 0.12065 -0.3048)
			(end 0.67945 -0.3048)
			(stroke
				(width 0.1)
				(type default)
			)
			(layer "F.Fab")
		)
		(fp_line
			(start 0.12065 -0.2794)
			(end 0.12065 -0.3048)
			(stroke
				(width 0.1)
				(type default)
			)
			(layer "F.Fab")
		)
		(fp_line
			(start 0.67945 -0.3048)
			(end 0.67945 0.3048)
			(stroke
				(width 0.1)
				(type default)
			)
			(layer "F.Fab")
		)
		(fp_line
			(start 0.67945 0.3048)
			(end 0.120396 0.3048)
			(stroke
				(width 0.1)
				(type default)
			)
			(layer "F.Fab")
		)
		(pad "1" smd circle
			(at -0.40005 0)
			(size 0 0)
			(layers "F.Cu" "F.Mask" "F.Paste")
			(net "P3V3_AUX")
		)
		(pad "2" smd circle
			(at 0.40005 0)
			(size 0 0)
			(layers "F.Cu" "F.Mask" "F.Paste")
			(net "HP_LVC3_SCM_HSC_PWRGD_R")
		)
	)
	(footprint ""
		(layer "F.Cu")
		(at 209.35188 -108.422948 90)
		(property "Reference" "R2339"
			(at 0 0 90)
			(layer "F.SilkS")
			(hide yes)
			(effects
				(font
					(size 1.27 1.27)
				)
			)
		)
		(property "Value" ""
			(at 0 0 90)
			(layer "F.Fab")
			(effects
				(font
					(size 1.27 1.27)
				)
			)
		)
		(duplicate_pad_numbers_are_jumpers no)
		(fp_line
			(start 0.7874 -0.4064)
			(end 0.7874 0.4064)
			(stroke
				(width 0.1524)
				(type default)
			)
			(layer "F.SilkS")
		)
		(fp_line
			(start -0.7874 -0.4064)
			(end 0.7874 -0.4064)
			(stroke
				(width 0.1524)
				(type default)
			)
			(layer "F.SilkS")
		)
		(fp_line
			(start 0.7874 0.4064)
			(end -0.7874 0.4064)
			(stroke
				(width 0.1524)
				(type default)
			)
			(layer "F.SilkS")
		)
		(fp_line
			(start -0.7874 0.4064)
			(end -0.7874 -0.4064)
			(stroke
				(width 0.1524)
				(type default)
			)
			(layer "F.SilkS")
		)
		(fp_line
			(start -0.12065 -0.305054)
			(end -0.12065 -0.2794)
			(stroke
				(width 0.1)
				(type default)
			)
			(layer "F.Fab")
		)
		(fp_line
			(start -0.67945 -0.305054)
			(end -0.12065 -0.305054)
			(stroke
				(width 0.1)
				(type default)
			)
			(layer "F.Fab")
		)
		(fp_line
			(start 0.67945 -0.3048)
			(end 0.67945 0.3048)
			(stroke
				(width 0.1)
				(type default)
			)
			(layer "F.Fab")
		)
		(fp_line
			(start 0.12065 -0.3048)
			(end 0.67945 -0.3048)
			(stroke
				(width 0.1)
				(type default)
			)
			(layer "F.Fab")
		)
		(fp_line
			(start 0.12065 -0.2794)
			(end 0.12065 -0.3048)
			(stroke
				(width 0.1)
				(type default)
			)
			(layer "F.Fab")
		)
		(fp_line
			(start -0.12065 -0.2794)
			(end 0.12065 -0.2794)
			(stroke
				(width 0.1)
				(type default)
			)
			(layer "F.Fab")
		)
		(fp_line
			(start 0.120396 0.2794)
			(end -0.12065 0.2794)
			(stroke
				(width 0.1)
				(type default)
			)
			(layer "F.Fab")
		)
		(fp_line
			(start -0.12065 0.2794)
			(end -0.12065 0.3048)
			(stroke
				(width 0.1)
				(type default)
			)
			(layer "F.Fab")
		)
		(fp_line
			(start 0.67945 0.3048)
			(end 0.120396 0.3048)
			(stroke
				(width 0.1)
				(type default)
			)
			(layer "F.Fab")
		)
		(fp_line
			(start 0.120396 0.3048)
			(end 0.120396 0.2794)
			(stroke
				(width 0.1)
				(type default)
			)
			(layer "F.Fab")
		)
		(fp_line
			(start -0.12065 0.3048)
			(end -0.67945 0.3048)
			(stroke
				(width 0.1)
				(type default)
			)
			(layer "F.Fab")
		)
		(fp_line
			(start -0.67945 0.3048)
			(end -0.67945 -0.305054)
			(stroke
				(width 0.1)
				(type default)
			)
			(layer "F.Fab")
		)
		(pad "1" smd circle
			(at -0.40005 0 90)
			(size 0 0)
			(layers "F.Cu" "F.Mask" "F.Paste")
			(net "LED_CPU_RMCA_CATERR_R")
		)
		(pad "2" smd circle
			(at 0.40005 0 90)
			(size 0 0)
			(layers "F.Cu" "F.Mask" "F.Paste")
			(net "GND")
		)
	)
)
